(kicad_pcb
	(version 20260206)
	(generator "pcbnew")
	(generator_version "10.0")
	(general
		(thickness 1.6)
		(legacy_teardrops no)
	)
	(paper "A4")
	(title_block
		(title "Bryce Canyon_IOM_M2_16342-2_OCP.brd")
		(comment 1 "Bryce Canyon / footprints 605-609 of 1146")
	)
	(layers
		(0 "F.Cu" signal "TOP")
		(4 "In1.Cu" signal "L2GND")
		(6 "In2.Cu" signal "L3")
		(8 "In3.Cu" signal "L4VCC")
		(10 "In4.Cu" signal "L5VCC")
		(12 "In5.Cu" signal "L6")
		(14 "In6.Cu" signal "L7GND")
		(2 "B.Cu" signal "BOTTOM")
		(9 "F.Adhes" user "F.Adhesive")
		(11 "B.Adhes" user "B.Adhesive")
		(13 "F.Paste" user "Package Geometry/Pastemask Top")
		(15 "B.Paste" user "Package Geometry/Pastemask Bottom")
		(5 "F.SilkS" user "Ref Des/Silkscreen Top")
		(7 "B.SilkS" user "Ref Des/Silkscreen Bottom")
		(1 "F.Mask" user "Board Geometry/Soldermask Top")
		(3 "B.Mask" user "Board Geometry/Soldermask Bottom")
		(17 "Dwgs.User" user "User.Drawings")
		(19 "Cmts.User" user "User.Comments")
		(21 "Eco1.User" user "User.Eco1")
		(23 "Eco2.User" user "User.Eco2")
		(25 "Edge.Cuts" user "Board Geometry/Outline")
		(27 "Margin" user)
		(31 "F.CrtYd" user "Package Geometry/Place Bound Top")
		(29 "B.CrtYd" user "Package Geometry/Place Bound Bottom")
		(35 "F.Fab" user "Ref Des/Assembly Top")
		(33 "B.Fab" user "Ref Des/Assembly Bottom")
	)
	(footprint ""
		(layer "F.Cu")
		(at 85.046058 -131.788662)
		(property "Reference" "R349"
			(at 0 0 0)
			(layer "F.SilkS")
			(hide yes)
			(effects
				(font
					(size 1.27 1.27)
				)
			)
		)
		(property "Value" "100KR2F-L1-GP"
			(at 0.064008 -3.993896 0)
			(unlocked yes)
			(layer "F.Fab")
			(hide yes)
			(effects
				(font
					(size 1.016 1.016)
					(thickness 0.1524)
				)
			)
		)
		(property "Device Type" "R402H16"
			(at 0.064008 -5.517896 0)
			(unlocked yes)
			(layer "F.Fab")
			(hide yes)
			(effects
				(font
					(size 1.016 1.016)
					(thickness 0.1524)
				)
			)
		)
		(duplicate_pad_numbers_are_jumpers no)
		(fp_line
			(start -0.508 -0.9398)
			(end -0.508 0.9398)
			(stroke
				(width 0.1524)
				(type default)
			)
			(layer "F.SilkS")
		)
		(fp_line
			(start 0.508 -0.9398)
			(end -0.508 -0.9398)
			(stroke
				(width 0.1524)
				(type default)
			)
			(layer "F.SilkS")
		)
		(fp_rect
			(start -0.508 0.9398)
			(end 0.508 -0.9398)
			(stroke
				(width 0)
				(type default)
			)
			(fill no)
			(layer "F.CrtYd")
		)
		(fp_rect
			(start -0.508 0.9398)
			(end 0.508 -0.9398)
			(stroke
				(width 0)
				(type default)
			)
			(fill no)
			(layer "F.Fab")
		)
		(pad "1" smd custom
			(at 0 -0.4445)
			(size 0.1397 0.1397)
			(layers "F.Cu" "F.Mask" "F.Paste")
			(net "P3V3_STBY")
			(options
				(clearance outline)
				(anchor circle)
			)
			(primitives
				(gr_poly
					(pts
						(arc
							(start -0.1778 -0.2794)
							(mid -0.249642 -0.249642)
							(end -0.2794 -0.1778)
						)
						(arc
							(start -0.2794 0.1778)
							(mid -0.249642 0.249642)
							(end -0.1778 0.2794)
						)
						(arc
							(start 0.1778 0.2794)
							(mid 0.249642 0.249642)
							(end 0.2794 0.1778)
						)
						(arc
							(start 0.2794 -0.1778)
							(mid 0.249642 -0.249642)
							(end 0.1778 -0.2794)
						)
					)
					(width 0)
					(fill yes)
				)
			)
		)
		(pad "2" smd custom
			(at 0 0.4445)
			(size 0.1397 0.1397)
			(layers "F.Cu" "F.Mask" "F.Paste")
			(net "DEBUG_UART_IOM_RX")
			(options
				(clearance outline)
				(anchor circle)
			)
			(primitives
				(gr_poly
					(pts
						(arc
							(start -0.1778 -0.2794)
							(mid -0.249642 -0.249642)
							(end -0.2794 -0.1778)
						)
						(arc
							(start -0.2794 0.1778)
							(mid -0.249642 0.249642)
							(end -0.1778 0.2794)
						)
						(arc
							(start 0.1778 0.2794)
							(mid 0.249642 0.249642)
							(end 0.2794 0.1778)
						)
						(arc
							(start 0.2794 -0.1778)
							(mid 0.249642 -0.249642)
							(end 0.1778 -0.2794)
						)
					)
					(width 0)
					(fill yes)
				)
			)
		)
	)
	(footprint ""
		(layer "F.Cu")
		(at 128.944116 -10.691622 -90)
		(property "Reference" "R710"
			(at 0 0 270)
			(layer "F.SilkS")
			(hide yes)
			(effects
				(font
					(size 1.27 1.27)
				)
			)
		)
		(property "Value" "0R5J-5-GP"
			(at 0 -8.9535 270)
			(unlocked yes)
			(layer "F.Fab")
			(hide yes)
			(effects
				(font
					(size 1.27 1.016)
					(thickness 0.1524)
				)
			)
		)
		(property "Device Type" "R805H24"
			(at 0 -10.6299 270)
			(unlocked yes)
			(layer "F.Fab")
			(hide yes)
			(effects
				(font
					(size 1.27 1.016)
					(thickness 0.1524)
				)
			)
		)
		(duplicate_pad_numbers_are_jumpers no)
		(fp_line
			(start -0.889 1.7018)
			(end 0.889 1.7018)
			(stroke
				(width 0.1524)
				(type default)
			)
			(layer "F.SilkS")
		)
		(fp_line
			(start 0.889 1.7018)
			(end 0.889 -0.508)
			(stroke
				(width 0.1524)
				(type default)
			)
			(layer "F.SilkS")
		)
		(fp_line
			(start -0.889 0.0762)
			(end -0.889 1.7018)
			(stroke
				(width 0.1524)
				(type default)
			)
			(layer "F.SilkS")
		)
		(fp_line
			(start -0.889 -1.7018)
			(end -0.889 0.2794)
			(stroke
				(width 0.1524)
				(type default)
			)
			(layer "F.SilkS")
		)
		(fp_line
			(start 0.889 -1.7018)
			(end 0.889 -0.381)
			(stroke
				(width 0.1524)
				(type default)
			)
			(layer "F.SilkS")
		)
		(fp_line
			(start 0.889 -1.7018)
			(end -0.889 -1.7018)
			(stroke
				(width 0.1524)
				(type default)
			)
			(layer "F.SilkS")
		)
		(fp_poly
			(pts
				(xy 0.9652 -1.778) (xy 0.9652 1.778) (xy -0.9652 1.778) (xy -0.9652 -1.778)
			)
			(stroke
				(width 0)
				(type default)
			)
			(fill no)
			(layer "F.CrtYd")
		)
		(fp_rect
			(start -0.9652 1.778)
			(end 0.9652 -1.778)
			(stroke
				(width 0)
				(type default)
			)
			(fill no)
			(layer "F.Fab")
		)
		(pad "1" smd rect
			(at 0 -0.9652 270)
			(size 1.397 1.143)
			(layers "F.Cu" "F.Mask" "F.Paste")
			(net "MB0_CM_GATE_R")
		)
		(pad "2" smd rect
			(at 0 0.9652 270)
			(size 1.397 1.143)
			(layers "F.Cu" "F.Mask" "F.Paste")
			(net "MB0_CM_GATE")
		)
	)
	(footprint ""
		(layer "F.Cu")
		(at 77.81798 -186.683396 180)
		(property "Reference" "C200"
			(at 0 0 180)
			(layer "F.SilkS")
			(hide yes)
			(effects
				(font
					(size 1.27 1.27)
				)
			)
		)
		(property "Value" "SC10U6D3V5KX-4GP"
			(at -0.0762 -6.1214 180)
			(unlocked yes)
			(layer "F.Fab")
			(hide yes)
			(effects
				(font
					(size 1.016 1.016)
					(thickness 0.1524)
				)
			)
		)
		(property "Device Type" "C805H58"
			(at -0.0762 -8.1534 180)
			(unlocked yes)
			(layer "F.Fab")
			(hide yes)
			(effects
				(font
					(size 1.016 1.016)
					(thickness 0.1524)
				)
			)
		)
		(duplicate_pad_numbers_are_jumpers no)
		(fp_line
			(start 0.635 0)
			(end -0.635 0)
			(stroke
				(width 0.508)
				(type default)
			)
			(layer "F.SilkS")
		)
		(fp_rect
			(start -0.9652 1.778)
			(end 0.9652 -1.778)
			(stroke
				(width 0)
				(type default)
			)
			(fill no)
			(layer "F.CrtYd")
		)
		(fp_poly
			(pts
				(xy -0.9652 -1.778) (xy 0.9652 -1.778) (xy 0.9652 1.778) (xy -0.9652 1.778)
			)
			(stroke
				(width 0)
				(type default)
			)
			(fill no)
			(layer "F.Fab")
		)
		(pad "1" smd rect
			(at 0 -0.9652 180)
			(size 1.397 1.143)
			(layers "F.Cu" "F.Mask" "F.Paste")
			(net "P3V3_STBY")
		)
		(pad "2" smd rect
			(at 0 0.9652 180)
			(size 1.397 1.143)
			(layers "F.Cu" "F.Mask" "F.Paste")
			(net "GND")
		)
	)
	(footprint ""
		(layer "F.Cu")
		(at 81.732882 -171.299378 -90)
		(property "Reference" "R651"
			(at 0 0 270)
			(layer "F.SilkS")
			(hide yes)
			(effects
				(font
					(size 1.27 1.27)
				)
			)
		)
		(property "Value" "0R2J-2-GP"
			(at 0.064008 -3.993896 270)
			(unlocked yes)
			(layer "F.Fab")
			(hide yes)
			(effects
				(font
					(size 1.016 1.016)
					(thickness 0.1524)
				)
			)
		)
		(property "Device Type" "R402H16"
			(at 0.064008 -5.517896 270)
			(unlocked yes)
			(layer "F.Fab")
			(hide yes)
			(effects
				(font
					(size 1.016 1.016)
					(thickness 0.1524)
				)
			)
		)
		(duplicate_pad_numbers_are_jumpers no)
		(fp_line
			(start -0.508 -0.9398)
			(end -0.508 0.9398)
			(stroke
				(width 0.1524)
				(type default)
			)
			(layer "F.SilkS")
		)
		(fp_line
			(start 0.508 -0.9398)
			(end -0.508 -0.9398)
			(stroke
				(width 0.1524)
				(type default)
			)
			(layer "F.SilkS")
		)
		(fp_rect
			(start -0.508 0.9398)
			(end 0.508 -0.9398)
			(stroke
				(width 0)
				(type default)
			)
			(fill no)
			(layer "F.CrtYd")
		)
		(fp_rect
			(start -0.508 0.9398)
			(end 0.508 -0.9398)
			(stroke
				(width 0)
				(type default)
			)
			(fill no)
			(layer "F.Fab")
		)
		(pad "1" smd custom
			(at 0 -0.4445 270)
			(size 0.1397 0.1397)
			(layers "F.Cu" "F.Mask" "F.Paste")
			(net "EXP_UART_EN_R")
			(options
				(clearance outline)
				(anchor circle)
			)
			(primitives
				(gr_poly
					(pts
						(arc
							(start -0.1778 -0.2794)
							(mid -0.249642 -0.249642)
							(end -0.2794 -0.1778)
						)
						(arc
							(start -0.2794 0.1778)
							(mid -0.249642 0.249642)
							(end -0.1778 0.2794)
						)
						(arc
							(start 0.1778 0.2794)
							(mid 0.249642 0.249642)
							(end 0.2794 0.1778)
						)
						(arc
							(start 0.2794 -0.1778)
							(mid 0.249642 -0.249642)
							(end 0.1778 -0.2794)
						)
					)
					(width 0)
					(fill yes)
				)
			)
		)
		(pad "2" smd custom
			(at 0 0.4445 270)
			(size 0.1397 0.1397)
			(layers "F.Cu" "F.Mask" "F.Paste")
			(net "EXP_UART_EN")
			(options
				(clearance outline)
				(anchor circle)
			)
			(primitives
				(gr_poly
					(pts
						(arc
							(start -0.1778 -0.2794)
							(mid -0.249642 -0.249642)
							(end -0.2794 -0.1778)
						)
						(arc
							(start -0.2794 0.1778)
							(mid -0.249642 0.249642)
							(end -0.1778 0.2794)
						)
						(arc
							(start 0.1778 0.2794)
							(mid 0.249642 0.249642)
							(end 0.2794 0.1778)
						)
						(arc
							(start 0.2794 -0.1778)
							(mid 0.249642 -0.249642)
							(end 0.1778 -0.2794)
						)
					)
					(width 0)
					(fill yes)
				)
			)
		)
	)
	(footprint ""
		(layer "F.Cu")
		(at 11.999976 -6.249924)
		(property "Reference" "RST1"
			(at 0 0 0)
			(layer "F.SilkS")
			(hide yes)
			(effects
				(font
					(size 1.27 1.27)
				)
			)
		)
		(property "Value" "SW-TACT-4P-210-GP"
			(at -5.9436 2.1209 0)
			(unlocked yes)
			(layer "F.Fab")
			(hide yes)
			(effects
				(font
					(size 1.016 1.016)
					(thickness 0.1524)
				)
			)
		)
		(property "Device Type" "DIPTRONICS"
			(at -5.9436 0.5969 0)
			(unlocked yes)
			(layer "F.Fab")
			(hide yes)
			(effects
				(font
					(size 1.016 1.016)
					(thickness 0.1524)
				)
			)
		)
		(duplicate_pad_numbers_are_jumpers no)
		(fp_line
			(start -4.4704 -4.2418)
			(end 4.4704 -4.2418)
			(stroke
				(width 0.1524)
				(type default)
			)
			(layer "F.SilkS")
		)
		(fp_line
			(start -4.4704 -1.5494)
			(end -4.4704 -4.2418)
			(stroke
				(width 0.1524)
				(type default)
			)
			(layer "F.SilkS")
		)
		(fp_line
			(start -3.9497 -1.5494)
			(end -4.4704 -1.5494)
			(stroke
				(width 0.1524)
				(type default)
			)
			(layer "F.SilkS")
		)
		(fp_line
			(start -3.9497 3.2258)
			(end -3.9497 -1.5494)
			(stroke
				(width 0.1524)
				(type default)
			)
			(layer "F.SilkS")
		)
		(fp_line
			(start -2.0066 3.2258)
			(end -3.9497 3.2258)
			(stroke
				(width 0.1524)
				(type default)
			)
			(layer "F.SilkS")
		)
		(fp_line
			(start -2.0066 6.1214)
			(end -2.0066 3.2258)
			(stroke
				(width 0.1524)
				(type default)
			)
			(layer "F.SilkS")
		)
		(fp_line
			(start 2.0066 3.2258)
			(end 2.0066 6.1214)
			(stroke
				(width 0.1524)
				(type default)
			)
			(layer "F.SilkS")
		)
		(fp_line
			(start 2.0066 6.1214)
			(end -2.0066 6.1214)
			(stroke
				(width 0.1524)
				(type default)
			)
			(layer "F.SilkS")
		)
		(fp_line
			(start 3.9497 -1.5494)
			(end 3.9497 3.2258)
			(stroke
				(width 0.1524)
				(type default)
			)
			(layer "F.SilkS")
		)
		(fp_line
			(start 3.9497 3.2258)
			(end 2.0066 3.2258)
			(stroke
				(width 0.1524)
				(type default)
			)
			(layer "F.SilkS")
		)
		(fp_line
			(start 4.4704 -4.2418)
			(end 4.4704 -1.5494)
			(stroke
				(width 0.1524)
				(type default)
			)
			(layer "F.SilkS")
		)
		(fp_line
			(start 4.4704 -1.5494)
			(end 3.9497 -1.5494)
			(stroke
				(width 0.1524)
				(type default)
			)
			(layer "F.SilkS")
		)
		(fp_circle
			(center -3.50012 -2.500122)
			(end -2.43332 -2.500122)
			(stroke
				(width 0.3048)
				(type default)
			)
			(fill no)
			(layer "F.SilkS")
		)
		(fp_circle
			(center -2.249932 0)
			(end -1.183132 0)
			(stroke
				(width 0.3048)
				(type default)
			)
			(fill no)
			(layer "F.SilkS")
		)
		(fp_circle
			(center 2.249932 0)
			(end 3.316732 0)
			(stroke
				(width 0.3048)
				(type default)
			)
			(fill no)
			(layer "F.SilkS")
		)
		(fp_circle
			(center 3.50012 -2.500122)
			(end 4.56692 -2.500122)
			(stroke
				(width 0.3048)
				(type default)
			)
			(fill no)
			(layer "F.SilkS")
		)
		(fp_poly
			(pts
				(xy -1.7526 5.8674) (xy -1.7526 2.9718) (xy -3.6957 2.9718) (xy -3.6957 -3.9878) (xy 3.6957 -3.9878)
				(xy 3.6957 2.9718) (xy 1.7526 2.9718) (xy 1.7526 5.8674)
			)
			(stroke
				(width 0)
				(type default)
			)
			(fill no)
			(layer "F.CrtYd")
		)
		(fp_poly
			(pts
				(xy -2.2606 6.3754) (xy -2.2606 3.4798) (xy -4.2037 3.4798) (xy -4.2037 -1.2954) (xy -4.7244 -1.2954)
				(xy -4.7244 -4.4958) (xy 4.7244 -4.4958) (xy 4.7244 -1.2954) (xy 4.2037 -1.2954) (xy 4.2037 -0.00635)
				(xy 3.6957 -0.00635) (xy 3.6957 -3.9878) (xy -3.6957 -3.9878) (xy -3.6957 2.9718) (xy -1.7526 2.9718)
				(xy -1.7526 5.8674) (xy 1.7526 5.8674) (xy 1.7526 2.9718) (xy 3.6957 2.9718) (xy 3.6957 0.00635)
				(xy 4.2037 0.00635) (xy 4.2037 3.4798) (xy 2.2606 3.4798) (xy 2.2606 6.3754)
			)
			(stroke
				(width 0)
				(type default)
			)
			(fill no)
			(layer "F.CrtYd")
		)
		(fp_poly
			(pts
				(xy -2.2606 6.3754) (xy -2.2606 3.4798) (xy -4.2037 3.4798) (xy -4.2037 -1.2954) (xy -4.7244 -1.2954)
				(xy -4.7244 -4.4958) (xy 4.7244 -4.4958) (xy 4.7244 -1.2954) (xy 4.2037 -1.2954) (xy 4.2037 3.4798)
				(xy 2.2606 3.4798) (xy 2.2606 6.3754)
			)
			(stroke
				(width 0)
				(type default)
			)
			(fill no)
			(layer "F.Fab")
		)
		(pad "1" thru_hole circle
			(at -2.249932 0)
			(size 1.4224 1.4224)
			(drill 1.016)
			(layers "*.Cu" "*.Mask")
			(remove_unused_layers no)
			(net "SYS_RST_BTN_IN_N")
			(clearance 0.1524)
			(thermal_gap 0.1524)
		)
		(pad "2" thru_hole circle
			(at 2.249932 0)
			(size 1.4224 1.4224)
			(drill 1.016)
			(layers "*.Cu" "*.Mask")
			(remove_unused_layers no)
			(net "GND")
			(clearance 0.1524)
			(thermal_gap 0.1524)
		)
		(pad "3" thru_hole circle
			(at -3.50012 -2.500122)
			(size 1.4224 1.4224)
			(drill 1.016)
			(layers "*.Cu" "*.Mask")
			(remove_unused_layers no)
			(net "RST_BTN_GND")
			(clearance 0.1524)
			(thermal_gap 0.1524)
		)
		(pad "4" thru_hole circle
			(at 3.50012 -2.500122)
			(size 1.4224 1.4224)
			(drill 1.016)
			(layers "*.Cu" "*.Mask")
			(remove_unused_layers no)
			(net "RST_BTN_GND")
			(clearance 0.1524)
			(thermal_gap 0.1524)
		)
		(zone
			(layer "F.Cu")
			(hatch none 0.5)
			(connect_pads
				(clearance 0)
			)
			(min_thickness 0.25)
			(keepout
				(tracks not_allowed)
				(vias allowed)
				(pads allowed)
				(copperpour not_allowed)
				(footprints allowed)
			)
			(placement
				(enabled no)
				(sheetname "")
			)
			(fill
				(thermal_gap 0.5)
				(thermal_bridge_width 0.5)
				(island_removal_mode 0)
			)
			(polygon
				(pts
					(xy 8.177276 -9.461246) (xy 8.837676 -9.461246) (xy 8.837676 -10.364724) (xy 8.177276 -10.364724)
				)
			)
		)
		(zone
			(layer "F.Cu")
			(hatch none 0.5)
			(connect_pads
				(clearance 0)
			)
			(min_thickness 0.25)
			(keepout
				(tracks allowed)
				(vias not_allowed)
				(pads allowed)
				(copperpour not_allowed)
				(footprints allowed)
			)
			(placement
				(enabled no)
				(sheetname "")
			)
			(fill
				(thermal_gap 0.5)
				(thermal_bridge_width 0.5)
				(island_removal_mode 0)
			)
			(polygon
				(pts
					(xy 8.177276 -9.461246) (xy 8.837676 -9.461246) (xy 8.837676 -10.364724) (xy 8.177276 -10.364724)
				)
			)
		)
		(zone
			(layer "F.Cu")
			(hatch none 0.5)
			(connect_pads
				(clearance 0)
			)
			(min_thickness 0.25)
			(keepout
				(tracks allowed)
				(vias not_allowed)
				(pads allowed)
				(copperpour not_allowed)
				(footprints allowed)
			)
			(placement
				(enabled no)
				(sheetname "")
			)
			(fill
				(thermal_gap 0.5)
				(thermal_bridge_width 0.5)
				(island_removal_mode 0)
			)
			(polygon
				(pts
					(xy 8.177276 -3.532124) (xy 8.837676 -3.532124) (xy 8.837676 -8.038846) (xy 8.177276 -8.038846)
				)
			)
		)
		(zone
			(layer "F.Cu")
			(hatch none 0.5)
			(connect_pads
				(clearance 0)
			)
			(min_thickness 0.25)
			(keepout
				(tracks not_allowed)
				(vias allowed)
				(pads allowed)
				(copperpour not_allowed)
				(footprints allowed)
			)
			(placement
				(enabled no)
				(sheetname "")
			)
			(fill
				(thermal_gap 0.5)
				(thermal_bridge_width 0.5)
				(island_removal_mode 0)
			)
			(polygon
				(pts
					(xy 8.177276 -3.532124) (xy 8.837676 -3.532124) (xy 8.837676 -8.038846) (xy 8.177276 -8.038846)
				)
			)
		)
		(zone
			(layer "F.Cu")
			(hatch none 0.5)
			(connect_pads
				(clearance 0)
			)
			(min_thickness 0.25)
			(keepout
				(tracks not_allowed)
				(vias allowed)
				(pads allowed)
				(copperpour not_allowed)
				(footprints allowed)
			)
			(placement
				(enabled no)
				(sheetname "")
			)
			(fill
				(thermal_gap 0.5)
				(thermal_bridge_width 0.5)
				(island_removal_mode 0)
			)
			(polygon
				(pts
					(xy 11.072876 -3.532124) (xy 12.927076 -3.532124) (xy 12.927076 -4.294124) (xy 11.072876 -4.294124)
				)
			)
		)
		(zone
			(layer "F.Cu")
			(hatch none 0.5)
			(connect_pads
				(clearance 0)
			)
			(min_thickness 0.25)
			(keepout
				(tracks allowed)
				(vias not_allowed)
				(pads allowed)
				(copperpour not_allowed)
				(footprints allowed)
			)
			(placement
				(enabled no)
				(sheetname "")
			)
			(fill
				(thermal_gap 0.5)
				(thermal_bridge_width 0.5)
				(island_removal_mode 0)
			)
			(polygon
				(pts
					(xy 11.072876 -3.532124) (xy 12.927076 -3.532124) (xy 12.927076 -4.294124) (xy 11.072876 -4.294124)
				)
			)
		)
		(zone
			(layer "F.Cu")
			(hatch none 0.5)
			(connect_pads
				(clearance 0)
			)
			(min_thickness 0.25)
			(keepout
				(tracks not_allowed)
				(vias allowed)
				(pads allowed)
				(copperpour not_allowed)
				(footprints allowed)
			)
			(placement
				(enabled no)
				(sheetname "")
			)
			(fill
				(thermal_gap 0.5)
				(thermal_bridge_width 0.5)
				(island_removal_mode 0)
			)
			(polygon
				(pts
					(xy 15.162276 -9.461246) (xy 15.822676 -9.461246) (xy 15.822676 -10.364724) (xy 15.162276 -10.364724)
				)
			)
		)
		(zone
			(layer "F.Cu")
			(hatch none 0.5)
			(connect_pads
				(clearance 0)
			)
			(min_thickness 0.25)
			(keepout
				(tracks allowed)
				(vias not_allowed)
				(pads allowed)
				(copperpour not_allowed)
				(footprints allowed)
			)
			(placement
				(enabled no)
				(sheetname "")
			)
			(fill
				(thermal_gap 0.5)
				(thermal_bridge_width 0.5)
				(island_removal_mode 0)
			)
			(polygon
				(pts
					(xy 15.162276 -9.461246) (xy 15.822676 -9.461246) (xy 15.822676 -10.364724) (xy 15.162276 -10.364724)
				)
			)
		)
		(zone
			(layer "F.Cu")
			(hatch none 0.5)
			(connect_pads
				(clearance 0)
			)
			(min_thickness 0.25)
			(keepout
				(tracks not_allowed)
				(vias allowed)
				(pads allowed)
				(copperpour not_allowed)
				(footprints allowed)
			)
			(placement
				(enabled no)
				(sheetname "")
			)
			(fill
				(thermal_gap 0.5)
				(thermal_bridge_width 0.5)
				(island_removal_mode 0)
			)
			(polygon
				(pts
					(xy 15.162276 -3.532124) (xy 15.822676 -3.532124) (xy 15.822676 -8.038846) (xy 15.162276 -8.038846)
				)
			)
		)
		(zone
			(layer "F.Cu")
			(hatch none 0.5)
			(connect_pads
				(clearance 0)
			)
			(min_thickness 0.25)
			(keepout
				(tracks allowed)
				(vias not_allowed)
				(pads allowed)
				(copperpour not_allowed)
				(footprints allowed)
			)
			(placement
				(enabled no)
				(sheetname "")
			)
			(fill
				(thermal_gap 0.5)
				(thermal_bridge_width 0.5)
				(island_removal_mode 0)
			)
			(polygon
				(pts
					(xy 15.162276 -3.532124) (xy 15.822676 -3.532124) (xy 15.822676 -8.038846) (xy 15.162276 -8.038846)
				)
			)
		)
	)
)
